(kicad_pcb
	(version 20260206)
	(generator "pcbnew")
	(generator_version "10.0")
	(general
		(thickness 1.6)
		(legacy_teardrops no)
	)
	(paper "A4")
	(title_block
		(title "Bryce Canyon_R.DPB_16317-1_OCP.brd")
		(comment 1 "Bryce Canyon / footprint 274 of 2099 (SAS1), pads 214-293 of 342")
	)
	(layers
		(0 "F.Cu" signal "TOP")
		(4 "In1.Cu" signal "L2GND")
		(6 "In2.Cu" signal "L3")
		(8 "In3.Cu" signal "L4VCC")
		(10 "In4.Cu" signal "L5VCC")
		(12 "In5.Cu" signal "L6")
		(14 "In6.Cu" signal "L7GND")
		(2 "B.Cu" signal "BOTTOM")
		(9 "F.Adhes" user "F.Adhesive")
		(11 "B.Adhes" user "B.Adhesive")
		(13 "F.Paste" user "Package Geometry/Pastemask Top")
		(15 "B.Paste" user "Package Geometry/Pastemask Bottom")
		(5 "F.SilkS" user "Ref Des/Silkscreen Top")
		(7 "B.SilkS" user "Ref Des/Silkscreen Bottom")
		(1 "F.Mask" user "Board Geometry/Soldermask Top")
		(3 "B.Mask" user "Board Geometry/Soldermask Bottom")
		(17 "Dwgs.User" user "User.Drawings")
		(19 "Cmts.User" user "User.Comments")
		(21 "Eco1.User" user "User.Eco1")
		(23 "Eco2.User" user "User.Eco2")
		(25 "Edge.Cuts" user "Board Geometry/Outline")
		(27 "Margin" user)
		(31 "F.CrtYd" user "Package Geometry/Place Bound Top")
		(29 "B.CrtYd" user "Package Geometry/Place Bound Bottom")
		(35 "F.Fab" user "Ref Des/Assembly Top")
		(33 "B.Fab" user "Ref Des/Assembly Bottom")
	)
	(footprint ""
		(layer "F.Cu")
		(at 287.83661 -238.694468 -90)
		(property "Reference" "SAS1"
			(at 0 0 270)
			(layer "F.SilkS")
			(hide yes)
			(effects
				(font
					(size 1.27 1.27)
				)
			)
		)
		(property "Value" "AMP-CONN342-10R-2-GP"
			(at 20.955 -16.7386 270)
			(unlocked yes)
			(layer "F.Fab")
			(hide yes)
			(effects
				(font
					(size 1.016 1.016)
					(thickness 0.1524)
				)
			)
		)
		(property "Device Type" "PREFIT-342P-668151H483"
			(at 20.955 -18.2626 270)
			(unlocked yes)
			(layer "F.Fab")
			(hide yes)
			(effects
				(font
					(size 1.016 1.016)
					(thickness 0.1524)
				)
			)
		)
		(duplicate_pad_numbers_are_jumpers no)
		(pad "F34" thru_hole circle
			(at 59.399932 9.59993 270)
			(size 0.762 0.762)
			(drill 0.359918)
			(layers "*.Cu" "*.Mask")
			(remove_unused_layers no)
			(net "PHY_SCC_B_TO_DRV_B_32_DN")
			(clearance 0.1651)
			(thermal_gap 0.1651)
		)
		(pad "F35" thru_hole circle
			(at 61.20003 8.599932 270)
			(size 0.762 0.762)
			(drill 0.359918)
			(layers "*.Cu" "*.Mask")
			(remove_unused_layers no)
			(net "PHY_SCC_B_TO_DRV_B_31_DN")
			(clearance 0.1651)
			(thermal_gap 0.1651)
		)
		(pad "F36" thru_hole circle
			(at 62.999874 9.59993 270)
			(size 0.762 0.762)
			(drill 0.359918)
			(layers "*.Cu" "*.Mask")
			(remove_unused_layers no)
			(net "PHY_SCC_B_TO_DRV_B_30_DN")
			(clearance 0.1651)
			(thermal_gap 0.1651)
		)
		(pad "GND1" thru_hole circle
			(at 0 2.500122 270)
			(size 0.762 0.762)
			(drill 0.359918)
			(layers "*.Cu" "*.Mask")
			(remove_unused_layers no)
			(net "GND")
			(clearance 0.1651)
			(thermal_gap 0.1651)
		)
		(pad "GND2" thru_hole circle
			(at 0 6.100064 270)
			(size 0.762 0.762)
			(drill 0.359918)
			(layers "*.Cu" "*.Mask")
			(remove_unused_layers no)
			(net "GND")
			(clearance 0.1651)
			(thermal_gap 0.1651)
		)
		(pad "GND3" thru_hole circle
			(at 0 9.700006 270)
			(size 0.762 0.762)
			(drill 0.359918)
			(layers "*.Cu" "*.Mask")
			(remove_unused_layers no)
			(net "GND")
			(clearance 0.1651)
			(thermal_gap 0.1651)
		)
		(pad "GND4" thru_hole circle
			(at 1.800098 -0.100076 270)
			(size 0.762 0.762)
			(drill 0.359918)
			(layers "*.Cu" "*.Mask")
			(remove_unused_layers no)
			(net "GND")
			(clearance 0.1651)
			(thermal_gap 0.1651)
		)
		(pad "GND5" thru_hole circle
			(at 1.800098 3.50012 270)
			(size 0.762 0.762)
			(drill 0.359918)
			(layers "*.Cu" "*.Mask")
			(remove_unused_layers no)
			(net "GND")
			(clearance 0.1651)
			(thermal_gap 0.1651)
		)
		(pad "GND6" thru_hole circle
			(at 1.800098 7.100062 270)
			(size 0.762 0.762)
			(drill 0.359918)
			(layers "*.Cu" "*.Mask")
			(remove_unused_layers no)
			(net "GND")
			(clearance 0.1651)
			(thermal_gap 0.1651)
		)
		(pad "GND7" thru_hole circle
			(at 1.800098 10.700004 270)
			(size 0.762 0.762)
			(drill 0.359918)
			(layers "*.Cu" "*.Mask")
			(remove_unused_layers no)
			(net "GND")
			(clearance 0.1651)
			(thermal_gap 0.1651)
		)
		(pad "GND8" thru_hole circle
			(at 3.599942 2.500122 270)
			(size 0.762 0.762)
			(drill 0.359918)
			(layers "*.Cu" "*.Mask")
			(remove_unused_layers no)
			(net "GND")
			(clearance 0.1651)
			(thermal_gap 0.1651)
		)
		(pad "GND9" thru_hole circle
			(at 3.599942 6.100064 270)
			(size 0.762 0.762)
			(drill 0.359918)
			(layers "*.Cu" "*.Mask")
			(remove_unused_layers no)
			(net "GND")
			(clearance 0.1651)
			(thermal_gap 0.1651)
		)
		(pad "GND10" thru_hole circle
			(at 3.599942 9.700006 270)
			(size 0.762 0.762)
			(drill 0.359918)
			(layers "*.Cu" "*.Mask")
			(remove_unused_layers no)
			(net "GND")
			(clearance 0.1651)
			(thermal_gap 0.1651)
		)
		(pad "GND11" thru_hole circle
			(at 5.40004 -0.100076 270)
			(size 0.762 0.762)
			(drill 0.359918)
			(layers "*.Cu" "*.Mask")
			(remove_unused_layers no)
			(net "GND")
			(clearance 0.1651)
			(thermal_gap 0.1651)
		)
		(pad "GND12" thru_hole circle
			(at 5.40004 3.50012 270)
			(size 0.762 0.762)
			(drill 0.359918)
			(layers "*.Cu" "*.Mask")
			(remove_unused_layers no)
			(net "GND")
			(clearance 0.1651)
			(thermal_gap 0.1651)
		)
		(pad "GND13" thru_hole circle
			(at 5.40004 7.100062 270)
			(size 0.762 0.762)
			(drill 0.359918)
			(layers "*.Cu" "*.Mask")
			(remove_unused_layers no)
			(net "GND")
			(clearance 0.1651)
			(thermal_gap 0.1651)
		)
		(pad "GND14" thru_hole circle
			(at 5.40004 10.700004 270)
			(size 0.762 0.762)
			(drill 0.359918)
			(layers "*.Cu" "*.Mask")
			(remove_unused_layers no)
			(net "GND")
			(clearance 0.1651)
			(thermal_gap 0.1651)
		)
		(pad "GND15" thru_hole circle
			(at 7.199884 2.500122 270)
			(size 0.762 0.762)
			(drill 0.359918)
			(layers "*.Cu" "*.Mask")
			(remove_unused_layers no)
			(net "GND")
			(clearance 0.1651)
			(thermal_gap 0.1651)
		)
		(pad "GND16" thru_hole circle
			(at 7.199884 6.100064 270)
			(size 0.762 0.762)
			(drill 0.359918)
			(layers "*.Cu" "*.Mask")
			(remove_unused_layers no)
			(net "GND")
			(clearance 0.1651)
			(thermal_gap 0.1651)
		)
		(pad "GND17" thru_hole circle
			(at 7.199884 9.700006 270)
			(size 0.762 0.762)
			(drill 0.359918)
			(layers "*.Cu" "*.Mask")
			(remove_unused_layers no)
			(net "GND")
			(clearance 0.1651)
			(thermal_gap 0.1651)
		)
		(pad "GND18" thru_hole circle
			(at 8.999982 -0.100076 270)
			(size 0.762 0.762)
			(drill 0.359918)
			(layers "*.Cu" "*.Mask")
			(remove_unused_layers no)
			(net "GND")
			(clearance 0.1651)
			(thermal_gap 0.1651)
		)
		(pad "GND19" thru_hole circle
			(at 8.999982 3.50012 270)
			(size 0.762 0.762)
			(drill 0.359918)
			(layers "*.Cu" "*.Mask")
			(remove_unused_layers no)
			(net "GND")
			(clearance 0.1651)
			(thermal_gap 0.1651)
		)
		(pad "GND20" thru_hole circle
			(at 8.999982 7.100062 270)
			(size 0.762 0.762)
			(drill 0.359918)
			(layers "*.Cu" "*.Mask")
			(remove_unused_layers no)
			(net "GND")
			(clearance 0.1651)
			(thermal_gap 0.1651)
		)
		(pad "GND21" thru_hole circle
			(at 8.999982 10.700004 270)
			(size 0.762 0.762)
			(drill 0.359918)
			(layers "*.Cu" "*.Mask")
			(remove_unused_layers no)
			(net "GND")
			(clearance 0.1651)
			(thermal_gap 0.1651)
		)
		(pad "GND22" thru_hole circle
			(at 10.80008 2.500122 270)
			(size 0.762 0.762)
			(drill 0.359918)
			(layers "*.Cu" "*.Mask")
			(remove_unused_layers no)
			(net "GND")
			(clearance 0.1651)
			(thermal_gap 0.1651)
		)
		(pad "GND23" thru_hole circle
			(at 10.80008 6.100064 270)
			(size 0.762 0.762)
			(drill 0.359918)
			(layers "*.Cu" "*.Mask")
			(remove_unused_layers no)
			(net "GND")
			(clearance 0.1651)
			(thermal_gap 0.1651)
		)
		(pad "GND24" thru_hole circle
			(at 10.80008 9.700006 270)
			(size 0.762 0.762)
			(drill 0.359918)
			(layers "*.Cu" "*.Mask")
			(remove_unused_layers no)
			(net "GND")
			(clearance 0.1651)
			(thermal_gap 0.1651)
		)
		(pad "GND25" thru_hole circle
			(at 12.599924 -0.100076 270)
			(size 0.762 0.762)
			(drill 0.359918)
			(layers "*.Cu" "*.Mask")
			(remove_unused_layers no)
			(net "GND")
			(clearance 0.1651)
			(thermal_gap 0.1651)
		)
		(pad "GND26" thru_hole circle
			(at 12.599924 3.50012 270)
			(size 0.762 0.762)
			(drill 0.359918)
			(layers "*.Cu" "*.Mask")
			(remove_unused_layers no)
			(net "GND")
			(clearance 0.1651)
			(thermal_gap 0.1651)
		)
		(pad "GND27" thru_hole circle
			(at 12.599924 7.100062 270)
			(size 0.762 0.762)
			(drill 0.359918)
			(layers "*.Cu" "*.Mask")
			(remove_unused_layers no)
			(net "GND")
			(clearance 0.1651)
			(thermal_gap 0.1651)
		)
		(pad "GND28" thru_hole circle
			(at 12.599924 10.700004 270)
			(size 0.762 0.762)
			(drill 0.359918)
			(layers "*.Cu" "*.Mask")
			(remove_unused_layers no)
			(net "GND")
			(clearance 0.1651)
			(thermal_gap 0.1651)
		)
		(pad "GND29" thru_hole circle
			(at 14.400022 2.500122 270)
			(size 0.762 0.762)
			(drill 0.359918)
			(layers "*.Cu" "*.Mask")
			(remove_unused_layers no)
			(net "GND")
			(clearance 0.1651)
			(thermal_gap 0.1651)
		)
		(pad "GND30" thru_hole circle
			(at 14.400022 6.100064 270)
			(size 0.762 0.762)
			(drill 0.359918)
			(layers "*.Cu" "*.Mask")
			(remove_unused_layers no)
			(net "GND")
			(clearance 0.1651)
			(thermal_gap 0.1651)
		)
		(pad "GND31" thru_hole circle
			(at 14.400022 9.700006 270)
			(size 0.762 0.762)
			(drill 0.359918)
			(layers "*.Cu" "*.Mask")
			(remove_unused_layers no)
			(net "GND")
			(clearance 0.1651)
			(thermal_gap 0.1651)
		)
		(pad "GND32" thru_hole circle
			(at 16.20012 -0.100076 270)
			(size 0.762 0.762)
			(drill 0.359918)
			(layers "*.Cu" "*.Mask")
			(remove_unused_layers no)
			(net "GND")
			(clearance 0.1651)
			(thermal_gap 0.1651)
		)
		(pad "GND33" thru_hole circle
			(at 16.20012 3.50012 270)
			(size 0.762 0.762)
			(drill 0.359918)
			(layers "*.Cu" "*.Mask")
			(remove_unused_layers no)
			(net "GND")
			(clearance 0.1651)
			(thermal_gap 0.1651)
		)
		(pad "GND34" thru_hole circle
			(at 16.20012 7.100062 270)
			(size 0.762 0.762)
			(drill 0.359918)
			(layers "*.Cu" "*.Mask")
			(remove_unused_layers no)
			(net "GND")
			(clearance 0.1651)
			(thermal_gap 0.1651)
		)
		(pad "GND35" thru_hole circle
			(at 16.20012 10.700004 270)
			(size 0.762 0.762)
			(drill 0.359918)
			(layers "*.Cu" "*.Mask")
			(remove_unused_layers no)
			(net "GND")
			(clearance 0.1651)
			(thermal_gap 0.1651)
		)
		(pad "GND36" thru_hole circle
			(at 17.999964 2.500122 270)
			(size 0.762 0.762)
			(drill 0.359918)
			(layers "*.Cu" "*.Mask")
			(remove_unused_layers no)
			(net "GND")
			(clearance 0.1651)
			(thermal_gap 0.1651)
		)
		(pad "GND37" thru_hole circle
			(at 17.999964 6.100064 270)
			(size 0.762 0.762)
			(drill 0.359918)
			(layers "*.Cu" "*.Mask")
			(remove_unused_layers no)
			(net "GND")
			(clearance 0.1651)
			(thermal_gap 0.1651)
		)
		(pad "GND38" thru_hole circle
			(at 17.999964 9.700006 270)
			(size 0.762 0.762)
			(drill 0.359918)
			(layers "*.Cu" "*.Mask")
			(remove_unused_layers no)
			(net "GND")
			(clearance 0.1651)
			(thermal_gap 0.1651)
		)
		(pad "GND39" thru_hole circle
			(at 19.800062 -0.100076 270)
			(size 0.762 0.762)
			(drill 0.359918)
			(layers "*.Cu" "*.Mask")
			(remove_unused_layers no)
			(net "GND")
			(clearance 0.1651)
			(thermal_gap 0.1651)
		)
		(pad "GND40" thru_hole circle
			(at 19.800062 3.50012 270)
			(size 0.762 0.762)
			(drill 0.359918)
			(layers "*.Cu" "*.Mask")
			(remove_unused_layers no)
			(net "GND")
			(clearance 0.1651)
			(thermal_gap 0.1651)
		)
		(pad "GND41" thru_hole circle
			(at 19.800062 7.100062 270)
			(size 0.762 0.762)
			(drill 0.359918)
			(layers "*.Cu" "*.Mask")
			(remove_unused_layers no)
			(net "GND")
			(clearance 0.1651)
			(thermal_gap 0.1651)
		)
		(pad "GND42" thru_hole circle
			(at 19.800062 10.700004 270)
			(size 0.762 0.762)
			(drill 0.359918)
			(layers "*.Cu" "*.Mask")
			(remove_unused_layers no)
			(net "GND")
			(clearance 0.1651)
			(thermal_gap 0.1651)
		)
		(pad "GND43" thru_hole circle
			(at 21.599906 2.500122 270)
			(size 0.762 0.762)
			(drill 0.359918)
			(layers "*.Cu" "*.Mask")
			(remove_unused_layers no)
			(net "GND")
			(clearance 0.1651)
			(thermal_gap 0.1651)
		)
		(pad "GND44" thru_hole circle
			(at 21.599906 6.100064 270)
			(size 0.762 0.762)
			(drill 0.359918)
			(layers "*.Cu" "*.Mask")
			(remove_unused_layers no)
			(net "GND")
			(clearance 0.1651)
			(thermal_gap 0.1651)
		)
		(pad "GND45" thru_hole circle
			(at 21.599906 9.700006 270)
			(size 0.762 0.762)
			(drill 0.359918)
			(layers "*.Cu" "*.Mask")
			(remove_unused_layers no)
			(net "GND")
			(clearance 0.1651)
			(thermal_gap 0.1651)
		)
		(pad "GND46" thru_hole circle
			(at 23.400004 -0.100076 270)
			(size 0.762 0.762)
			(drill 0.359918)
			(layers "*.Cu" "*.Mask")
			(remove_unused_layers no)
			(net "GND")
			(clearance 0.1651)
			(thermal_gap 0.1651)
		)
		(pad "GND47" thru_hole circle
			(at 23.400004 3.50012 270)
			(size 0.762 0.762)
			(drill 0.359918)
			(layers "*.Cu" "*.Mask")
			(remove_unused_layers no)
			(net "GND")
			(clearance 0.1651)
			(thermal_gap 0.1651)
		)
		(pad "GND48" thru_hole circle
			(at 23.400004 7.100062 270)
			(size 0.762 0.762)
			(drill 0.359918)
			(layers "*.Cu" "*.Mask")
			(remove_unused_layers no)
			(net "GND")
			(clearance 0.1651)
			(thermal_gap 0.1651)
		)
		(pad "GND49" thru_hole circle
			(at 23.400004 10.700004 270)
			(size 0.762 0.762)
			(drill 0.359918)
			(layers "*.Cu" "*.Mask")
			(remove_unused_layers no)
			(net "GND")
			(clearance 0.1651)
			(thermal_gap 0.1651)
		)
		(pad "GND50" thru_hole circle
			(at 25.200102 2.500122 270)
			(size 0.762 0.762)
			(drill 0.359918)
			(layers "*.Cu" "*.Mask")
			(remove_unused_layers no)
			(net "GND")
			(clearance 0.1651)
			(thermal_gap 0.1651)
		)
		(pad "GND51" thru_hole circle
			(at 25.200102 6.100064 270)
			(size 0.762 0.762)
			(drill 0.359918)
			(layers "*.Cu" "*.Mask")
			(remove_unused_layers no)
			(net "GND")
			(clearance 0.1651)
			(thermal_gap 0.1651)
		)
		(pad "GND52" thru_hole circle
			(at 25.200102 9.700006 270)
			(size 0.762 0.762)
			(drill 0.359918)
			(layers "*.Cu" "*.Mask")
			(remove_unused_layers no)
			(net "GND")
			(clearance 0.1651)
			(thermal_gap 0.1651)
		)
		(pad "GND53" thru_hole circle
			(at 26.999946 -0.100076 270)
			(size 0.762 0.762)
			(drill 0.359918)
			(layers "*.Cu" "*.Mask")
			(remove_unused_layers no)
			(net "GND")
			(clearance 0.1651)
			(thermal_gap 0.1651)
		)
		(pad "GND54" thru_hole circle
			(at 26.999946 3.50012 270)
			(size 0.762 0.762)
			(drill 0.359918)
			(layers "*.Cu" "*.Mask")
			(remove_unused_layers no)
			(net "GND")
			(clearance 0.1651)
			(thermal_gap 0.1651)
		)
		(pad "GND55" thru_hole circle
			(at 26.999946 7.100062 270)
			(size 0.762 0.762)
			(drill 0.359918)
			(layers "*.Cu" "*.Mask")
			(remove_unused_layers no)
			(net "GND")
			(clearance 0.1651)
			(thermal_gap 0.1651)
		)
		(pad "GND56" thru_hole circle
			(at 26.999946 10.700004 270)
			(size 0.762 0.762)
			(drill 0.359918)
			(layers "*.Cu" "*.Mask")
			(remove_unused_layers no)
			(net "GND")
			(clearance 0.1651)
			(thermal_gap 0.1651)
		)
		(pad "GND57" thru_hole circle
			(at 28.800044 2.500122 270)
			(size 0.762 0.762)
			(drill 0.359918)
			(layers "*.Cu" "*.Mask")
			(remove_unused_layers no)
			(net "GND")
			(clearance 0.1651)
			(thermal_gap 0.1651)
		)
		(pad "GND58" thru_hole circle
			(at 28.800044 6.100064 270)
			(size 0.762 0.762)
			(drill 0.359918)
			(layers "*.Cu" "*.Mask")
			(remove_unused_layers no)
			(net "GND")
			(clearance 0.1651)
			(thermal_gap 0.1651)
		)
		(pad "GND59" thru_hole circle
			(at 28.800044 9.700006 270)
			(size 0.762 0.762)
			(drill 0.359918)
			(layers "*.Cu" "*.Mask")
			(remove_unused_layers no)
			(net "GND")
			(clearance 0.1651)
			(thermal_gap 0.1651)
		)
		(pad "GND60" thru_hole circle
			(at 30.599888 -0.100076 270)
			(size 0.762 0.762)
			(drill 0.359918)
			(layers "*.Cu" "*.Mask")
			(remove_unused_layers no)
			(net "GND")
			(clearance 0.1651)
			(thermal_gap 0.1651)
		)
		(pad "GND61" thru_hole circle
			(at 30.599888 3.50012 270)
			(size 0.762 0.762)
			(drill 0.359918)
			(layers "*.Cu" "*.Mask")
			(remove_unused_layers no)
			(net "GND")
			(clearance 0.1651)
			(thermal_gap 0.1651)
		)
		(pad "GND62" thru_hole circle
			(at 30.599888 7.100062 270)
			(size 0.762 0.762)
			(drill 0.359918)
			(layers "*.Cu" "*.Mask")
			(remove_unused_layers no)
			(net "GND")
			(clearance 0.1651)
			(thermal_gap 0.1651)
		)
		(pad "GND63" thru_hole circle
			(at 30.599888 10.700004 270)
			(size 0.762 0.762)
			(drill 0.359918)
			(layers "*.Cu" "*.Mask")
			(remove_unused_layers no)
			(net "GND")
			(clearance 0.1651)
			(thermal_gap 0.1651)
		)
		(pad "GND64" thru_hole circle
			(at 32.399986 2.500122 270)
			(size 0.762 0.762)
			(drill 0.359918)
			(layers "*.Cu" "*.Mask")
			(remove_unused_layers no)
			(net "GND")
			(clearance 0.1651)
			(thermal_gap 0.1651)
		)
		(pad "GND65" thru_hole circle
			(at 32.399986 6.100064 270)
			(size 0.762 0.762)
			(drill 0.359918)
			(layers "*.Cu" "*.Mask")
			(remove_unused_layers no)
			(net "GND")
			(clearance 0.1651)
			(thermal_gap 0.1651)
		)
		(pad "GND66" thru_hole circle
			(at 32.399986 9.700006 270)
			(size 0.762 0.762)
			(drill 0.359918)
			(layers "*.Cu" "*.Mask")
			(remove_unused_layers no)
			(net "GND")
			(clearance 0.1651)
			(thermal_gap 0.1651)
		)
		(pad "GND67" thru_hole circle
			(at 34.200084 -0.100076 270)
			(size 0.762 0.762)
			(drill 0.359918)
			(layers "*.Cu" "*.Mask")
			(remove_unused_layers no)
			(net "GND")
			(clearance 0.1651)
			(thermal_gap 0.1651)
		)
		(pad "GND68" thru_hole circle
			(at 34.200084 3.50012 270)
			(size 0.762 0.762)
			(drill 0.359918)
			(layers "*.Cu" "*.Mask")
			(remove_unused_layers no)
			(net "GND")
			(clearance 0.1651)
			(thermal_gap 0.1651)
		)
		(pad "GND69" thru_hole circle
			(at 34.200084 7.100062 270)
			(size 0.762 0.762)
			(drill 0.359918)
			(layers "*.Cu" "*.Mask")
			(remove_unused_layers no)
			(net "GND")
			(clearance 0.1651)
			(thermal_gap 0.1651)
		)
		(pad "GND70" thru_hole circle
			(at 34.200084 10.700004 270)
			(size 0.762 0.762)
			(drill 0.359918)
			(layers "*.Cu" "*.Mask")
			(remove_unused_layers no)
			(net "GND")
			(clearance 0.1651)
			(thermal_gap 0.1651)
		)
		(pad "GND71" thru_hole circle
			(at 35.999928 2.500122 270)
			(size 0.762 0.762)
			(drill 0.359918)
			(layers "*.Cu" "*.Mask")
			(remove_unused_layers no)
			(net "GND")
			(clearance 0.1651)
			(thermal_gap 0.1651)
		)
		(pad "GND72" thru_hole circle
			(at 35.999928 6.100064 270)
			(size 0.762 0.762)
			(drill 0.359918)
			(layers "*.Cu" "*.Mask")
			(remove_unused_layers no)
			(net "GND")
			(clearance 0.1651)
			(thermal_gap 0.1651)
		)
		(pad "GND73" thru_hole circle
			(at 35.999928 9.700006 270)
			(size 0.762 0.762)
			(drill 0.359918)
			(layers "*.Cu" "*.Mask")
			(remove_unused_layers no)
			(net "GND")
			(clearance 0.1651)
			(thermal_gap 0.1651)
		)
		(pad "GND74" thru_hole circle
			(at 37.800026 -0.100076 270)
			(size 0.762 0.762)
			(drill 0.359918)
			(layers "*.Cu" "*.Mask")
			(remove_unused_layers no)
			(net "GND")
			(clearance 0.1651)
			(thermal_gap 0.1651)
		)
		(pad "GND75" thru_hole circle
			(at 37.800026 3.50012 270)
			(size 0.762 0.762)
			(drill 0.359918)
			(layers "*.Cu" "*.Mask")
			(remove_unused_layers no)
			(net "GND")
			(clearance 0.1651)
			(thermal_gap 0.1651)
		)
		(pad "GND76" thru_hole circle
			(at 37.800026 7.100062 270)
			(size 0.762 0.762)
			(drill 0.359918)
			(layers "*.Cu" "*.Mask")
			(remove_unused_layers no)
			(net "GND")
			(clearance 0.1651)
			(thermal_gap 0.1651)
		)
		(pad "GND77" thru_hole circle
			(at 37.800026 10.700004 270)
			(size 0.762 0.762)
			(drill 0.359918)
			(layers "*.Cu" "*.Mask")
			(remove_unused_layers no)
			(net "GND")
			(clearance 0.1651)
			(thermal_gap 0.1651)
		)
	)
)
